(kicad_pcb
	(version 20260206)
	(generator "pcbnew")
	(generator_version "10.0")
	(general
		(thickness 1.6)
		(legacy_teardrops no)
	)
	(paper "A4")
	(title_block
		(title "04192023_DAF0TMB3IC0_F0TG_MB_C_brd_V02_OCP.brd")
		(comment 1 "Grand Teton / footprints 5083-5089 of 8354")
	)
	(layers
		(0 "F.Cu" signal "TOP")
		(4 "In1.Cu" signal "GND")
		(6 "In2.Cu" signal "IN1")
		(8 "In3.Cu" signal "GND1")
		(10 "In4.Cu" signal "IN2")
		(12 "In5.Cu" signal "GND2")
		(14 "In6.Cu" signal "IN3")
		(16 "In7.Cu" signal "GND3")
		(18 "In8.Cu" signal "VCC")
		(20 "In9.Cu" signal "VCC1")
		(22 "In10.Cu" signal "GND4")
		(24 "In11.Cu" signal "IN4")
		(26 "In12.Cu" signal "GND5")
		(28 "In13.Cu" signal "IN5")
		(30 "In14.Cu" signal "GND6")
		(32 "In15.Cu" signal "IN6")
		(34 "In16.Cu" signal "GND7")
		(2 "B.Cu" signal "BOTTOM")
		(9 "F.Adhes" user "F.Adhesive")
		(11 "B.Adhes" user "B.Adhesive")
		(13 "F.Paste" user "Package Geometry/Pastemask Top")
		(15 "B.Paste" user "Package Geometry/Pastemask Bottom")
		(5 "F.SilkS" user "Ref Des/Silkscreen Top")
		(7 "B.SilkS" user "Ref Des/Silkscreen Bottom")
		(1 "F.Mask" user "Board Geometry/Soldermask Top")
		(3 "B.Mask" user "Board Geometry/Soldermask Bottom")
		(17 "Dwgs.User" user "User.Drawings")
		(19 "Cmts.User" user "User.Comments")
		(21 "Eco1.User" user "User.Eco1")
		(23 "Eco2.User" user "User.Eco2")
		(25 "Edge.Cuts" user "Board Geometry/Outline")
		(27 "Margin" user)
		(31 "F.CrtYd" user "Package Geometry/Place Bound Top")
		(29 "B.CrtYd" user "Package Geometry/Place Bound Bottom")
		(35 "F.Fab" user "Ref Des/Assembly Top")
		(33 "B.Fab" user "Ref Des/Assembly Bottom")
	)
	(footprint ""
		(layer "B.Cu")
		(at 352.247454 -251.78131)
		(property "Reference" "C2588"
			(at 0 0 0)
			(layer "B.SilkS")
			(hide yes)
			(effects
				(font
					(size 1.27 1.27)
				)
				(justify mirror)
			)
		)
		(property "Value" ""
			(at 0 0 0)
			(layer "B.Fab")
			(effects
				(font
					(size 1.27 1.27)
				)
				(justify mirror)
			)
		)
		(duplicate_pad_numbers_are_jumpers no)
		(fp_line
			(start -0.7874 -0.4064)
			(end -0.7874 0.4064)
			(stroke
				(width 0.1524)
				(type default)
			)
			(layer "B.SilkS")
		)
		(fp_line
			(start -0.7874 0.4064)
			(end 0.7874 0.4064)
			(stroke
				(width 0.1524)
				(type default)
			)
			(layer "B.SilkS")
		)
		(fp_line
			(start 0.7874 -0.4064)
			(end -0.7874 -0.4064)
			(stroke
				(width 0.1524)
				(type default)
			)
			(layer "B.SilkS")
		)
		(fp_line
			(start 0.7874 0.4064)
			(end 0.7874 -0.4064)
			(stroke
				(width 0.1524)
				(type default)
			)
			(layer "B.SilkS")
		)
		(fp_line
			(start -0.67945 -0.3048)
			(end -0.67945 0.3048)
			(stroke
				(width 0.1)
				(type default)
			)
			(layer "B.Fab")
		)
		(fp_line
			(start -0.67945 0.3048)
			(end -0.120396 0.3048)
			(stroke
				(width 0.1)
				(type default)
			)
			(layer "B.Fab")
		)
		(fp_line
			(start -0.12065 -0.3048)
			(end -0.67945 -0.3048)
			(stroke
				(width 0.1)
				(type default)
			)
			(layer "B.Fab")
		)
		(fp_line
			(start -0.12065 -0.2794)
			(end -0.12065 -0.3048)
			(stroke
				(width 0.1)
				(type default)
			)
			(layer "B.Fab")
		)
		(fp_line
			(start -0.120396 0.2794)
			(end 0.12065 0.2794)
			(stroke
				(width 0.1)
				(type default)
			)
			(layer "B.Fab")
		)
		(fp_line
			(start -0.120396 0.3048)
			(end -0.120396 0.2794)
			(stroke
				(width 0.1)
				(type default)
			)
			(layer "B.Fab")
		)
		(fp_line
			(start 0.12065 -0.305054)
			(end 0.12065 -0.2794)
			(stroke
				(width 0.1)
				(type default)
			)
			(layer "B.Fab")
		)
		(fp_line
			(start 0.12065 -0.2794)
			(end -0.12065 -0.2794)
			(stroke
				(width 0.1)
				(type default)
			)
			(layer "B.Fab")
		)
		(fp_line
			(start 0.12065 0.2794)
			(end 0.12065 0.3048)
			(stroke
				(width 0.1)
				(type default)
			)
			(layer "B.Fab")
		)
		(fp_line
			(start 0.12065 0.3048)
			(end 0.67945 0.3048)
			(stroke
				(width 0.1)
				(type default)
			)
			(layer "B.Fab")
		)
		(fp_line
			(start 0.67945 -0.305054)
			(end 0.12065 -0.305054)
			(stroke
				(width 0.1)
				(type default)
			)
			(layer "B.Fab")
		)
		(fp_line
			(start 0.67945 0.3048)
			(end 0.67945 -0.305054)
			(stroke
				(width 0.1)
				(type default)
			)
			(layer "B.Fab")
		)
		(pad "1" smd circle
			(at 0.40005 0 180)
			(size 0 0)
			(layers "B.Cu" "B.Mask" "B.Paste")
			(net "PVDDCR_SOC_P0")
		)
		(pad "2" smd circle
			(at -0.40005 0 180)
			(size 0 0)
			(layers "B.Cu" "B.Mask" "B.Paste")
			(net "GND")
		)
	)
	(footprint ""
		(layer "B.Cu")
		(at 48.618902 -421.460676)
		(property "Reference" "Q96"
			(at 0.70104 -1.773682 0)
			(unlocked yes)
			(layer "B.SilkS")
			(effects
				(font
					(size 0.7874 0.5842)
					(thickness 0.1524)
				)
				(justify left mirror)
			)
		)
		(property "Value" ""
			(at 0 0 0)
			(layer "B.Fab")
			(effects
				(font
					(size 1.27 1.27)
				)
				(justify mirror)
			)
		)
		(duplicate_pad_numbers_are_jumpers no)
		(fp_line
			(start -1.332738 -1.100074)
			(end -1.332738 1.100074)
			(stroke
				(width 0.1524)
				(type default)
			)
			(layer "B.SilkS")
		)
		(fp_line
			(start -1.332738 1.100074)
			(end 1.332738 1.100074)
			(stroke
				(width 0.1524)
				(type default)
			)
			(layer "B.SilkS")
		)
		(fp_line
			(start -0.4826 -1.100074)
			(end -1.332738 -1.100074)
			(stroke
				(width 0.1524)
				(type default)
			)
			(layer "B.SilkS")
		)
		(fp_line
			(start 0 -0.541274)
			(end -0.4826 -1.100074)
			(stroke
				(width 0.1524)
				(type default)
			)
			(layer "B.SilkS")
		)
		(fp_line
			(start 0.4826 -1.100074)
			(end 0 -0.541274)
			(stroke
				(width 0.1524)
				(type default)
			)
			(layer "B.SilkS")
		)
		(fp_line
			(start 1.332738 -1.100074)
			(end 0.4826 -1.100074)
			(stroke
				(width 0.1524)
				(type default)
			)
			(layer "B.SilkS")
		)
		(fp_line
			(start 1.332738 1.100074)
			(end 1.332738 -1.100074)
			(stroke
				(width 0.1524)
				(type default)
			)
			(layer "B.SilkS")
		)
		(fp_poly
			(pts
				(xy 1.039114 -1.794002) (xy 1.373378 -2.504186) (xy 0.671576 -2.487676)
			)
			(stroke
				(width 0)
				(type default)
			)
			(fill yes)
			(layer "B.SilkS")
		)
		(fp_line
			(start -0.674878 -1.100074)
			(end -0.674878 1.100074)
			(stroke
				(width 0.1)
				(type default)
			)
			(layer "B.Fab")
		)
		(fp_line
			(start -0.674878 1.100074)
			(end 0.674878 1.100074)
			(stroke
				(width 0.1)
				(type default)
			)
			(layer "B.Fab")
		)
		(fp_line
			(start 0.674878 -1.100074)
			(end -0.674878 -1.100074)
			(stroke
				(width 0.1)
				(type default)
			)
			(layer "B.Fab")
		)
		(fp_line
			(start 0.674878 1.100074)
			(end 0.674878 -1.100074)
			(stroke
				(width 0.1)
				(type default)
			)
			(layer "B.Fab")
		)
		(fp_poly
			(pts
				(xy 2.2352 -0.298958) (xy 2.2352 -1.001014) (xy 1.533144 -0.649986)
			)
			(stroke
				(width 0)
				(type default)
			)
			(fill yes)
			(layer "B.Fab")
		)
		(pad "1" smd rect
			(at 0.94996 -0.649986 90)
			(size 0.4318 0.508)
			(layers "B.Cu" "B.Mask" "B.Paste")
			(net "GND")
		)
		(pad "2" smd rect
			(at 0.94996 0 90)
			(size 0.4318 0.508)
			(layers "B.Cu" "B.Mask" "B.Paste")
			(net "GPU_FPGA_READY")
		)
		(pad "3" smd rect
			(at 0.94996 0.649986 90)
			(size 0.4318 0.508)
			(layers "B.Cu" "B.Mask" "B.Paste")
			(net "GPU_FPGA_READY_ISO")
		)
		(pad "4" smd rect
			(at -0.94996 0.649986 90)
			(size 0.4318 0.508)
			(layers "B.Cu" "B.Mask" "B.Paste")
			(net "GND")
		)
		(pad "5" smd rect
			(at -0.94996 0 90)
			(size 0.4318 0.508)
			(layers "B.Cu" "B.Mask" "B.Paste")
			(net "GPU_FPGA_READY_N")
		)
		(pad "6" smd rect
			(at -0.94996 -0.649986 90)
			(size 0.4318 0.508)
			(layers "B.Cu" "B.Mask" "B.Paste")
			(net "GPU_FPGA_READY_N")
		)
	)
	(footprint ""
		(layer "B.Cu")
		(at 254.635 -330.962 180)
		(property "Reference" "R850"
			(at 0 0 0)
			(layer "B.SilkS")
			(hide yes)
			(effects
				(font
					(size 1.27 1.27)
				)
				(justify mirror)
			)
		)
		(property "Value" ""
			(at 0 0 0)
			(layer "B.Fab")
			(effects
				(font
					(size 1.27 1.27)
				)
				(justify mirror)
			)
		)
		(duplicate_pad_numbers_are_jumpers no)
		(fp_line
			(start 0.32512 0.175006)
			(end 0.32512 -0.175006)
			(stroke
				(width 0.1)
				(type default)
			)
			(layer "B.Fab")
		)
		(fp_line
			(start 0.32512 -0.175006)
			(end -0.32512 -0.175006)
			(stroke
				(width 0.1)
				(type default)
			)
			(layer "B.Fab")
		)
		(fp_line
			(start -0.32512 0.175006)
			(end 0.32512 0.175006)
			(stroke
				(width 0.1)
				(type default)
			)
			(layer "B.Fab")
		)
		(fp_line
			(start -0.32512 -0.175006)
			(end -0.32512 0.175006)
			(stroke
				(width 0.1)
				(type default)
			)
			(layer "B.Fab")
		)
		(pad "1" smd rect
			(at 0.2667 0)
			(size 0.3048 0.381)
			(layers "B.Cu" "B.Mask" "B.Paste")
			(net "SMB_MUX_RT_ROM_SDA")
		)
		(pad "2" smd rect
			(at -0.2667 0 180)
			(size 0.3048 0.381)
			(layers "B.Cu" "B.Mask" "B.Paste")
			(net "SMB_MUX_RT_ROM_R1_SDA")
		)
	)
	(footprint ""
		(layer "B.Cu")
		(at 68.098162 -336.059272 -90)
		(property "Reference" "PR265"
			(at 0 0 90)
			(layer "B.SilkS")
			(hide yes)
			(effects
				(font
					(size 1.27 1.27)
				)
				(justify mirror)
			)
		)
		(property "Value" ""
			(at 0 0 90)
			(layer "B.Fab")
			(effects
				(font
					(size 1.27 1.27)
				)
				(justify mirror)
			)
		)
		(duplicate_pad_numbers_are_jumpers no)
		(fp_line
			(start -0.7874 0.4064)
			(end 0.7874 0.4064)
			(stroke
				(width 0.1524)
				(type default)
			)
			(layer "B.SilkS")
		)
		(fp_line
			(start 0.7874 0.4064)
			(end 0.7874 -0.4064)
			(stroke
				(width 0.1524)
				(type default)
			)
			(layer "B.SilkS")
		)
		(fp_line
			(start -0.7874 -0.4064)
			(end -0.7874 0.4064)
			(stroke
				(width 0.1524)
				(type default)
			)
			(layer "B.SilkS")
		)
		(fp_line
			(start 0.7874 -0.4064)
			(end -0.7874 -0.4064)
			(stroke
				(width 0.1524)
				(type default)
			)
			(layer "B.SilkS")
		)
		(fp_line
			(start -0.67945 0.3048)
			(end -0.120396 0.3048)
			(stroke
				(width 0.1)
				(type default)
			)
			(layer "B.Fab")
		)
		(fp_line
			(start -0.120396 0.3048)
			(end -0.120396 0.2794)
			(stroke
				(width 0.1)
				(type default)
			)
			(layer "B.Fab")
		)
		(fp_line
			(start 0.12065 0.3048)
			(end 0.67945 0.3048)
			(stroke
				(width 0.1)
				(type default)
			)
			(layer "B.Fab")
		)
		(fp_line
			(start 0.67945 0.3048)
			(end 0.67945 -0.305054)
			(stroke
				(width 0.1)
				(type default)
			)
			(layer "B.Fab")
		)
		(fp_line
			(start -0.120396 0.2794)
			(end 0.12065 0.2794)
			(stroke
				(width 0.1)
				(type default)
			)
			(layer "B.Fab")
		)
		(fp_line
			(start 0.12065 0.2794)
			(end 0.12065 0.3048)
			(stroke
				(width 0.1)
				(type default)
			)
			(layer "B.Fab")
		)
		(fp_line
			(start -0.12065 -0.2794)
			(end -0.12065 -0.3048)
			(stroke
				(width 0.1)
				(type default)
			)
			(layer "B.Fab")
		)
		(fp_line
			(start 0.12065 -0.2794)
			(end -0.12065 -0.2794)
			(stroke
				(width 0.1)
				(type default)
			)
			(layer "B.Fab")
		)
		(fp_line
			(start -0.67945 -0.3048)
			(end -0.67945 0.3048)
			(stroke
				(width 0.1)
				(type default)
			)
			(layer "B.Fab")
		)
		(fp_line
			(start -0.12065 -0.3048)
			(end -0.67945 -0.3048)
			(stroke
				(width 0.1)
				(type default)
			)
			(layer "B.Fab")
		)
		(fp_line
			(start 0.12065 -0.305054)
			(end 0.12065 -0.2794)
			(stroke
				(width 0.1)
				(type default)
			)
			(layer "B.Fab")
		)
		(fp_line
			(start 0.67945 -0.305054)
			(end 0.12065 -0.305054)
			(stroke
				(width 0.1)
				(type default)
			)
			(layer "B.Fab")
		)
		(pad "1" smd circle
			(at 0.40005 0 90)
			(size 0 0)
			(layers "B.Cu" "B.Mask" "B.Paste")
			(net "PVDDCR_CPU1_P1_PVCC")
		)
		(pad "2" smd circle
			(at -0.40005 0 90)
			(size 0 0)
			(layers "B.Cu" "B.Mask" "B.Paste")
			(net "PVDDCR_CPU1_P1_VCC3")
		)
	)
	(footprint ""
		(layer "B.Cu")
		(at 186.758834 -342.261952 -90)
		(property "Reference" "PC527_2"
			(at 0 0 90)
			(layer "B.SilkS")
			(hide yes)
			(effects
				(font
					(size 1.27 1.27)
				)
				(justify mirror)
			)
		)
		(property "Value" ""
			(at 0 0 90)
			(layer "B.Fab")
			(effects
				(font
					(size 1.27 1.27)
				)
				(justify mirror)
			)
		)
		(duplicate_pad_numbers_are_jumpers no)
		(fp_line
			(start -1.524 0.762)
			(end 1.524 0.762)
			(stroke
				(width 0.1524)
				(type default)
			)
			(layer "B.SilkS")
		)
		(fp_line
			(start 1.524 0.762)
			(end 1.524 -0.762)
			(stroke
				(width 0.1524)
				(type default)
			)
			(layer "B.SilkS")
		)
		(fp_line
			(start -1.524 -0.762)
			(end -1.524 0.762)
			(stroke
				(width 0.1524)
				(type default)
			)
			(layer "B.SilkS")
		)
		(fp_line
			(start 1.524 -0.762)
			(end -1.524 -0.762)
			(stroke
				(width 0.1524)
				(type default)
			)
			(layer "B.SilkS")
		)
		(fp_line
			(start -1.1049 0.724916)
			(end -1.1049 -0.724916)
			(stroke
				(width 0.1)
				(type default)
			)
			(layer "B.Fab")
		)
		(fp_line
			(start 1.1049 0.724916)
			(end -1.1049 0.724916)
			(stroke
				(width 0.1)
				(type default)
			)
			(layer "B.Fab")
		)
		(fp_line
			(start -1.1049 -0.724916)
			(end 1.1049 -0.724916)
			(stroke
				(width 0.1)
				(type default)
			)
			(layer "B.Fab")
		)
		(fp_line
			(start 1.1049 -0.724916)
			(end 1.1049 0.724916)
			(stroke
				(width 0.1)
				(type default)
			)
			(layer "B.Fab")
		)
		(pad "1" smd rect
			(at 0.889 0 270)
			(size 1.016 1.27)
			(layers "B.Cu" "B.Mask" "B.Paste")
			(net "PVDD11_S3_P1")
		)
		(pad "2" smd rect
			(at -0.889 0 270)
			(size 1.016 1.27)
			(layers "B.Cu" "B.Mask" "B.Paste")
			(net "GND")
		)
	)
	(footprint ""
		(layer "B.Cu")
		(at 384.113278 -142.234158 180)
		(property "Reference" "PC472"
			(at 0 0 0)
			(layer "B.SilkS")
			(hide yes)
			(effects
				(font
					(size 1.27 1.27)
				)
				(justify mirror)
			)
		)
		(property "Value" ""
			(at 0 0 0)
			(layer "B.Fab")
			(effects
				(font
					(size 1.27 1.27)
				)
				(justify mirror)
			)
		)
		(duplicate_pad_numbers_are_jumpers no)
		(fp_line
			(start 0.7874 0.4064)
			(end 0.7874 -0.4064)
			(stroke
				(width 0.1524)
				(type default)
			)
			(layer "B.SilkS")
		)
		(fp_line
			(start 0.7874 -0.4064)
			(end -0.7874 -0.4064)
			(stroke
				(width 0.1524)
				(type default)
			)
			(layer "B.SilkS")
		)
		(fp_line
			(start -0.7874 0.4064)
			(end 0.7874 0.4064)
			(stroke
				(width 0.1524)
				(type default)
			)
			(layer "B.SilkS")
		)
		(fp_line
			(start -0.7874 -0.4064)
			(end -0.7874 0.4064)
			(stroke
				(width 0.1524)
				(type default)
			)
			(layer "B.SilkS")
		)
		(fp_line
			(start 0.67945 0.3048)
			(end 0.67945 -0.305054)
			(stroke
				(width 0.1)
				(type default)
			)
			(layer "B.Fab")
		)
		(fp_line
			(start 0.67945 -0.305054)
			(end 0.12065 -0.305054)
			(stroke
				(width 0.1)
				(type default)
			)
			(layer "B.Fab")
		)
		(fp_line
			(start 0.12065 0.3048)
			(end 0.67945 0.3048)
			(stroke
				(width 0.1)
				(type default)
			)
			(layer "B.Fab")
		)
		(fp_line
			(start 0.12065 0.2794)
			(end 0.12065 0.3048)
			(stroke
				(width 0.1)
				(type default)
			)
			(layer "B.Fab")
		)
		(fp_line
			(start 0.12065 -0.2794)
			(end -0.12065 -0.2794)
			(stroke
				(width 0.1)
				(type default)
			)
			(layer "B.Fab")
		)
		(fp_line
			(start 0.12065 -0.305054)
			(end 0.12065 -0.2794)
			(stroke
				(width 0.1)
				(type default)
			)
			(layer "B.Fab")
		)
		(fp_line
			(start -0.120396 0.3048)
			(end -0.120396 0.2794)
			(stroke
				(width 0.1)
				(type default)
			)
			(layer "B.Fab")
		)
		(fp_line
			(start -0.120396 0.2794)
			(end 0.12065 0.2794)
			(stroke
				(width 0.1)
				(type default)
			)
			(layer "B.Fab")
		)
		(fp_line
			(start -0.12065 -0.2794)
			(end -0.12065 -0.3048)
			(stroke
				(width 0.1)
				(type default)
			)
			(layer "B.Fab")
		)
		(fp_line
			(start -0.12065 -0.3048)
			(end -0.67945 -0.3048)
			(stroke
				(width 0.1)
				(type default)
			)
			(layer "B.Fab")
		)
		(fp_line
			(start -0.67945 0.3048)
			(end -0.120396 0.3048)
			(stroke
				(width 0.1)
				(type default)
			)
			(layer "B.Fab")
		)
		(fp_line
			(start -0.67945 -0.3048)
			(end -0.67945 0.3048)
			(stroke
				(width 0.1)
				(type default)
			)
			(layer "B.Fab")
		)
		(pad "1" smd circle
			(at 0.40005 0)
			(size 0 0)
			(layers "B.Cu" "B.Mask" "B.Paste")
			(net "PVDDCR_SOC_P0_TEMP1")
		)
		(pad "2" smd circle
			(at -0.40005 0)
			(size 0 0)
			(layers "B.Cu" "B.Mask" "B.Paste")
			(net "GND")
		)
	)
	(footprint ""
		(layer "B.Cu")
		(at 124.173234 -269.313152 180)
		(property "Reference" "C2363"
			(at 0 0 0)
			(layer "B.SilkS")
			(hide yes)
			(effects
				(font
					(size 1.27 1.27)
				)
				(justify mirror)
			)
		)
		(property "Value" ""
			(at 0 0 0)
			(layer "B.Fab")
			(effects
				(font
					(size 1.27 1.27)
				)
				(justify mirror)
			)
		)
		(duplicate_pad_numbers_are_jumpers no)
		(fp_line
			(start 0.7874 0.4064)
			(end 0.7874 -0.4064)
			(stroke
				(width 0.1524)
				(type default)
			)
			(layer "B.SilkS")
		)
		(fp_line
			(start 0.7874 -0.4064)
			(end -0.7874 -0.4064)
			(stroke
				(width 0.1524)
				(type default)
			)
			(layer "B.SilkS")
		)
		(fp_line
			(start -0.7874 0.4064)
			(end 0.7874 0.4064)
			(stroke
				(width 0.1524)
				(type default)
			)
			(layer "B.SilkS")
		)
		(fp_line
			(start -0.7874 -0.4064)
			(end -0.7874 0.4064)
			(stroke
				(width 0.1524)
				(type default)
			)
			(layer "B.SilkS")
		)
		(fp_line
			(start 0.67945 0.3048)
			(end 0.67945 -0.305054)
			(stroke
				(width 0.1)
				(type default)
			)
			(layer "B.Fab")
		)
		(fp_line
			(start 0.67945 -0.305054)
			(end 0.12065 -0.305054)
			(stroke
				(width 0.1)
				(type default)
			)
			(layer "B.Fab")
		)
		(fp_line
			(start 0.12065 0.3048)
			(end 0.67945 0.3048)
			(stroke
				(width 0.1)
				(type default)
			)
			(layer "B.Fab")
		)
		(fp_line
			(start 0.12065 0.2794)
			(end 0.12065 0.3048)
			(stroke
				(width 0.1)
				(type default)
			)
			(layer "B.Fab")
		)
		(fp_line
			(start 0.12065 -0.2794)
			(end -0.12065 -0.2794)
			(stroke
				(width 0.1)
				(type default)
			)
			(layer "B.Fab")
		)
		(fp_line
			(start 0.12065 -0.305054)
			(end 0.12065 -0.2794)
			(stroke
				(width 0.1)
				(type default)
			)
			(layer "B.Fab")
		)
		(fp_line
			(start -0.120396 0.3048)
			(end -0.120396 0.2794)
			(stroke
				(width 0.1)
				(type default)
			)
			(layer "B.Fab")
		)
		(fp_line
			(start -0.120396 0.2794)
			(end 0.12065 0.2794)
			(stroke
				(width 0.1)
				(type default)
			)
			(layer "B.Fab")
		)
		(fp_line
			(start -0.12065 -0.2794)
			(end -0.12065 -0.3048)
			(stroke
				(width 0.1)
				(type default)
			)
			(layer "B.Fab")
		)
		(fp_line
			(start -0.12065 -0.3048)
			(end -0.67945 -0.3048)
			(stroke
				(width 0.1)
				(type default)
			)
			(layer "B.Fab")
		)
		(fp_line
			(start -0.67945 0.3048)
			(end -0.120396 0.3048)
			(stroke
				(width 0.1)
				(type default)
			)
			(layer "B.Fab")
		)
		(fp_line
			(start -0.67945 -0.3048)
			(end -0.67945 0.3048)
			(stroke
				(width 0.1)
				(type default)
			)
			(layer "B.Fab")
		)
		(pad "1" smd circle
			(at 0.40005 0)
			(size 0 0)
			(layers "B.Cu" "B.Mask" "B.Paste")
			(net "PVDDCR_CPU1_P1")
		)
		(pad "2" smd circle
			(at -0.40005 0)
			(size 0 0)
			(layers "B.Cu" "B.Mask" "B.Paste")
			(net "GND")
		)
	)
)
